#ISCELL
  pure_quanta quanta_title_block_c *
  *
#CELL
  pure_quanta pt5161lrs *
  page417_i1
#ISCELL
  standard tap *
  page417_i10
#ISCELL
  standard tap *
  page417_i11
#ISCELL
  standard tap *
  page417_i12
#ISCELL
  standard tap *
  page417_i13
#ISCELL
  standard tap *
  page417_i14
#ISCELL
  standard tap *
  page417_i15
#ISCELL
  standard tap *
  page417_i16
#ISCELL
  standard tap *
  page417_i17
#ISCELL
  standard offpage *
  page417_i18
#ISCELL
  standard offpage *
  page417_i19
#ISCELL
  standard tap *
  page417_i2
#ISCELL
  standard tap *
  page417_i20
#ISCELL
  standard tap *
  page417_i21
#ISCELL
  standard tap *
  page417_i22
#ISCELL
  standard tap *
  page417_i23
#ISCELL
  standard tap *
  page417_i24
#ISCELL
  standard tap *
  page417_i25
#ISCELL
  standard tap *
  page417_i26
#ISCELL
  standard tap *
  page417_i27
#ISCELL
  standard tap *
  page417_i28
#ISCELL
  standard tap *
  page417_i29
#ISCELL
  standard tap *
  page417_i3
#ISCELL
  standard tap *
  page417_i30
#ISCELL
  standard tap *
  page417_i31
#ISCELL
  standard tap *
  page417_i32
#ISCELL
  standard tap *
  page417_i33
#ISCELL
  standard tap *
  page417_i34
#ISCELL
  standard tap *
  page417_i35
#ISCELL
  standard offpage *
  page417_i36
#ISCELL
  standard offpage *
  page417_i37
#CELL
  pure_quanta pt5161lrs *
  page417_i38
#ISCELL
  standard tap *
  page417_i4
#ISCELL
  standard tap *
  page417_i5
#ISCELL
  standard tap *
  page417_i6
#ISCELL
  standard tap *
  page417_i7
#ISCELL
  standard tap *
  page417_i8
#ISCELL
  standard tap *
  page417_i9
